(kicad_pcb
	(version 20260206)
	(generator "pcbnew")
	(generator_version "10.0")
	(general
		(thickness 1.6)
		(legacy_teardrops no)
	)
	(paper "A4")
	(title_block
		(title "03242023_DA0F0TMBIJ0_F0T_Motherboard_J_brd_V01_OCP.brd")
		(comment 1 "Grand Teton / footprints 508-514 of 6105")
	)
	(layers
		(0 "F.Cu" signal "TOP")
		(4 "In1.Cu" signal "GND")
		(6 "In2.Cu" signal "IN1")
		(8 "In3.Cu" signal "GND1")
		(10 "In4.Cu" signal "IN2")
		(12 "In5.Cu" signal "GND2")
		(14 "In6.Cu" signal "IN3")
		(16 "In7.Cu" signal "GND3")
		(18 "In8.Cu" signal "VCC")
		(20 "In9.Cu" signal "VCC1")
		(22 "In10.Cu" signal "GND4")
		(24 "In11.Cu" signal "IN4")
		(26 "In12.Cu" signal "GND5")
		(28 "In13.Cu" signal "IN5")
		(30 "In14.Cu" signal "GND6")
		(32 "In15.Cu" signal "IN6")
		(34 "In16.Cu" signal "GND7")
		(2 "B.Cu" signal "BOTTOM")
		(9 "F.Adhes" user "F.Adhesive")
		(11 "B.Adhes" user "B.Adhesive")
		(13 "F.Paste" user "Package Geometry/Pastemask Top")
		(15 "B.Paste" user "Package Geometry/Pastemask Bottom")
		(5 "F.SilkS" user "Ref Des/Silkscreen Top")
		(7 "B.SilkS" user "Ref Des/Silkscreen Bottom")
		(1 "F.Mask" user "Board Geometry/Soldermask Top")
		(3 "B.Mask" user "Board Geometry/Soldermask Bottom")
		(17 "Dwgs.User" user "User.Drawings")
		(19 "Cmts.User" user "User.Comments")
		(21 "Eco1.User" user "User.Eco1")
		(23 "Eco2.User" user "User.Eco2")
		(25 "Edge.Cuts" user "Board Geometry/Outline")
		(27 "Margin" user)
		(31 "F.CrtYd" user "Package Geometry/Place Bound Top")
		(29 "B.CrtYd" user "Package Geometry/Place Bound Bottom")
		(35 "F.Fab" user "Ref Des/Assembly Top")
		(33 "B.Fab" user "Ref Des/Assembly Bottom")
	)
	(footprint ""
		(layer "F.Cu")
		(at 114.81308 -400.414998 -90)
		(property "Reference" "R3030"
			(at 0 0 270)
			(layer "F.SilkS")
			(hide yes)
			(effects
				(font
					(size 1.27 1.27)
				)
			)
		)
		(property "Value" ""
			(at 0 0 270)
			(layer "F.Fab")
			(effects
				(font
					(size 1.27 1.27)
				)
			)
		)
		(duplicate_pad_numbers_are_jumpers no)
		(fp_line
			(start -0.7874 0.4064)
			(end -0.7874 -0.4064)
			(stroke
				(width 0.1524)
				(type default)
			)
			(layer "F.SilkS")
		)
		(fp_line
			(start 0.7874 0.4064)
			(end -0.7874 0.4064)
			(stroke
				(width 0.1524)
				(type default)
			)
			(layer "F.SilkS")
		)
		(fp_line
			(start -0.7874 -0.4064)
			(end 0.7874 -0.4064)
			(stroke
				(width 0.1524)
				(type default)
			)
			(layer "F.SilkS")
		)
		(fp_line
			(start 0.7874 -0.4064)
			(end 0.7874 0.4064)
			(stroke
				(width 0.1524)
				(type default)
			)
			(layer "F.SilkS")
		)
		(fp_line
			(start -0.67945 0.3048)
			(end -0.67945 -0.305054)
			(stroke
				(width 0.1)
				(type default)
			)
			(layer "F.Fab")
		)
		(fp_line
			(start -0.12065 0.3048)
			(end -0.67945 0.3048)
			(stroke
				(width 0.1)
				(type default)
			)
			(layer "F.Fab")
		)
		(fp_line
			(start 0.120396 0.3048)
			(end 0.120396 0.2794)
			(stroke
				(width 0.1)
				(type default)
			)
			(layer "F.Fab")
		)
		(fp_line
			(start 0.67945 0.3048)
			(end 0.120396 0.3048)
			(stroke
				(width 0.1)
				(type default)
			)
			(layer "F.Fab")
		)
		(fp_line
			(start -0.12065 0.2794)
			(end -0.12065 0.3048)
			(stroke
				(width 0.1)
				(type default)
			)
			(layer "F.Fab")
		)
		(fp_line
			(start 0.120396 0.2794)
			(end -0.12065 0.2794)
			(stroke
				(width 0.1)
				(type default)
			)
			(layer "F.Fab")
		)
		(fp_line
			(start -0.12065 -0.2794)
			(end 0.12065 -0.2794)
			(stroke
				(width 0.1)
				(type default)
			)
			(layer "F.Fab")
		)
		(fp_line
			(start 0.12065 -0.2794)
			(end 0.12065 -0.3048)
			(stroke
				(width 0.1)
				(type default)
			)
			(layer "F.Fab")
		)
		(fp_line
			(start 0.12065 -0.3048)
			(end 0.67945 -0.3048)
			(stroke
				(width 0.1)
				(type default)
			)
			(layer "F.Fab")
		)
		(fp_line
			(start 0.67945 -0.3048)
			(end 0.67945 0.3048)
			(stroke
				(width 0.1)
				(type default)
			)
			(layer "F.Fab")
		)
		(fp_line
			(start -0.67945 -0.305054)
			(end -0.12065 -0.305054)
			(stroke
				(width 0.1)
				(type default)
			)
			(layer "F.Fab")
		)
		(fp_line
			(start -0.12065 -0.305054)
			(end -0.12065 -0.2794)
			(stroke
				(width 0.1)
				(type default)
			)
			(layer "F.Fab")
		)
		(pad "1" smd circle
			(at -0.40005 0 270)
			(size 0 0)
			(layers "F.Cu" "F.Mask" "F.Paste")
			(net "P3V3_AUX")
		)
		(pad "2" smd circle
			(at 0.40005 0 270)
			(size 0 0)
			(layers "F.Cu" "F.Mask" "F.Paste")
			(net "FM_SMB_1_ALERT_GPU_ISO_N")
		)
	)
	(footprint ""
		(layer "F.Cu")
		(at 272.394934 -67.455796 180)
		(property "Reference" "PC1224"
			(at 0 0 180)
			(layer "F.SilkS")
			(hide yes)
			(effects
				(font
					(size 1.27 1.27)
				)
			)
		)
		(property "Value" ""
			(at 0 0 180)
			(layer "F.Fab")
			(effects
				(font
					(size 1.27 1.27)
				)
			)
		)
		(duplicate_pad_numbers_are_jumpers no)
		(fp_line
			(start 0.7874 0.4064)
			(end -0.7874 0.4064)
			(stroke
				(width 0.1524)
				(type default)
			)
			(layer "F.SilkS")
		)
		(fp_line
			(start 0.7874 -0.4064)
			(end 0.7874 0.4064)
			(stroke
				(width 0.1524)
				(type default)
			)
			(layer "F.SilkS")
		)
		(fp_line
			(start -0.7874 0.4064)
			(end -0.7874 -0.4064)
			(stroke
				(width 0.1524)
				(type default)
			)
			(layer "F.SilkS")
		)
		(fp_line
			(start -0.7874 -0.4064)
			(end 0.7874 -0.4064)
			(stroke
				(width 0.1524)
				(type default)
			)
			(layer "F.SilkS")
		)
		(fp_line
			(start 0.67945 0.3048)
			(end 0.120396 0.3048)
			(stroke
				(width 0.1)
				(type default)
			)
			(layer "F.Fab")
		)
		(fp_line
			(start 0.67945 -0.3048)
			(end 0.67945 0.3048)
			(stroke
				(width 0.1)
				(type default)
			)
			(layer "F.Fab")
		)
		(fp_line
			(start 0.12065 -0.2794)
			(end 0.12065 -0.3048)
			(stroke
				(width 0.1)
				(type default)
			)
			(layer "F.Fab")
		)
		(fp_line
			(start 0.12065 -0.3048)
			(end 0.67945 -0.3048)
			(stroke
				(width 0.1)
				(type default)
			)
			(layer "F.Fab")
		)
		(fp_line
			(start 0.120396 0.3048)
			(end 0.120396 0.2794)
			(stroke
				(width 0.1)
				(type default)
			)
			(layer "F.Fab")
		)
		(fp_line
			(start 0.120396 0.2794)
			(end -0.12065 0.2794)
			(stroke
				(width 0.1)
				(type default)
			)
			(layer "F.Fab")
		)
		(fp_line
			(start -0.12065 0.3048)
			(end -0.67945 0.3048)
			(stroke
				(width 0.1)
				(type default)
			)
			(layer "F.Fab")
		)
		(fp_line
			(start -0.12065 0.2794)
			(end -0.12065 0.3048)
			(stroke
				(width 0.1)
				(type default)
			)
			(layer "F.Fab")
		)
		(fp_line
			(start -0.12065 -0.2794)
			(end 0.12065 -0.2794)
			(stroke
				(width 0.1)
				(type default)
			)
			(layer "F.Fab")
		)
		(fp_line
			(start -0.12065 -0.305054)
			(end -0.12065 -0.2794)
			(stroke
				(width 0.1)
				(type default)
			)
			(layer "F.Fab")
		)
		(fp_line
			(start -0.67945 0.3048)
			(end -0.67945 -0.305054)
			(stroke
				(width 0.1)
				(type default)
			)
			(layer "F.Fab")
		)
		(fp_line
			(start -0.67945 -0.305054)
			(end -0.12065 -0.305054)
			(stroke
				(width 0.1)
				(type default)
			)
			(layer "F.Fab")
		)
		(pad "1" smd circle
			(at -0.40005 0 180)
			(size 0 0)
			(layers "F.Cu" "F.Mask" "F.Paste")
			(net "P1V05_PCH_AUX")
		)
		(pad "2" smd circle
			(at 0.40005 0 180)
			(size 0 0)
			(layers "F.Cu" "F.Mask" "F.Paste")
			(net "GND")
		)
	)
	(footprint ""
		(layer "F.Cu")
		(at 437.425846 -381.47498 180)
		(property "Reference" "PC1856"
			(at 0 0 180)
			(layer "F.SilkS")
			(hide yes)
			(effects
				(font
					(size 1.27 1.27)
				)
			)
		)
		(property "Value" ""
			(at 0 0 180)
			(layer "F.Fab")
			(effects
				(font
					(size 1.27 1.27)
				)
			)
		)
		(duplicate_pad_numbers_are_jumpers no)
		(fp_line
			(start 1.524 0.762)
			(end -1.524 0.762)
			(stroke
				(width 0.1524)
				(type default)
			)
			(layer "F.SilkS")
		)
		(fp_line
			(start 1.524 -0.762)
			(end 1.524 0.762)
			(stroke
				(width 0.1524)
				(type default)
			)
			(layer "F.SilkS")
		)
		(fp_line
			(start -1.524 0.762)
			(end -1.524 -0.762)
			(stroke
				(width 0.1524)
				(type default)
			)
			(layer "F.SilkS")
		)
		(fp_line
			(start -1.524 -0.762)
			(end 1.524 -0.762)
			(stroke
				(width 0.1524)
				(type default)
			)
			(layer "F.SilkS")
		)
		(fp_line
			(start 1.1049 0.724916)
			(end 1.1049 -0.724916)
			(stroke
				(width 0.1)
				(type default)
			)
			(layer "F.Fab")
		)
		(fp_line
			(start 1.1049 -0.724916)
			(end -1.1049 -0.724916)
			(stroke
				(width 0.1)
				(type default)
			)
			(layer "F.Fab")
		)
		(fp_line
			(start -1.1049 0.724916)
			(end 1.1049 0.724916)
			(stroke
				(width 0.1)
				(type default)
			)
			(layer "F.Fab")
		)
		(fp_line
			(start -1.1049 -0.724916)
			(end -1.1049 0.724916)
			(stroke
				(width 0.1)
				(type default)
			)
			(layer "F.Fab")
		)
		(pad "1" smd rect
			(at -0.889 0)
			(size 1.016 1.27)
			(layers "F.Cu" "F.Mask" "F.Paste")
			(net "P5V_AUX")
		)
		(pad "2" smd rect
			(at 0.889 0)
			(size 1.016 1.27)
			(layers "F.Cu" "F.Mask" "F.Paste")
			(net "GND")
		)
	)
	(footprint ""
		(layer "F.Cu")
		(at 22.13356 -164.735256)
		(property "Reference" "R2579"
			(at 0 0 0)
			(layer "F.SilkS")
			(hide yes)
			(effects
				(font
					(size 1.27 1.27)
				)
			)
		)
		(property "Value" ""
			(at 0 0 0)
			(layer "F.Fab")
			(effects
				(font
					(size 1.27 1.27)
				)
			)
		)
		(duplicate_pad_numbers_are_jumpers no)
		(fp_line
			(start -0.7874 -0.4064)
			(end 0.7874 -0.4064)
			(stroke
				(width 0.1524)
				(type default)
			)
			(layer "F.SilkS")
		)
		(fp_line
			(start -0.7874 0.4064)
			(end -0.7874 -0.4064)
			(stroke
				(width 0.1524)
				(type default)
			)
			(layer "F.SilkS")
		)
		(fp_line
			(start 0.7874 -0.4064)
			(end 0.7874 0.4064)
			(stroke
				(width 0.1524)
				(type default)
			)
			(layer "F.SilkS")
		)
		(fp_line
			(start 0.7874 0.4064)
			(end -0.7874 0.4064)
			(stroke
				(width 0.1524)
				(type default)
			)
			(layer "F.SilkS")
		)
		(fp_line
			(start -0.67945 -0.305054)
			(end -0.12065 -0.305054)
			(stroke
				(width 0.1)
				(type default)
			)
			(layer "F.Fab")
		)
		(fp_line
			(start -0.67945 0.3048)
			(end -0.67945 -0.305054)
			(stroke
				(width 0.1)
				(type default)
			)
			(layer "F.Fab")
		)
		(fp_line
			(start -0.12065 -0.305054)
			(end -0.12065 -0.2794)
			(stroke
				(width 0.1)
				(type default)
			)
			(layer "F.Fab")
		)
		(fp_line
			(start -0.12065 -0.2794)
			(end 0.12065 -0.2794)
			(stroke
				(width 0.1)
				(type default)
			)
			(layer "F.Fab")
		)
		(fp_line
			(start -0.12065 0.2794)
			(end -0.12065 0.3048)
			(stroke
				(width 0.1)
				(type default)
			)
			(layer "F.Fab")
		)
		(fp_line
			(start -0.12065 0.3048)
			(end -0.67945 0.3048)
			(stroke
				(width 0.1)
				(type default)
			)
			(layer "F.Fab")
		)
		(fp_line
			(start 0.120396 0.2794)
			(end -0.12065 0.2794)
			(stroke
				(width 0.1)
				(type default)
			)
			(layer "F.Fab")
		)
		(fp_line
			(start 0.120396 0.3048)
			(end 0.120396 0.2794)
			(stroke
				(width 0.1)
				(type default)
			)
			(layer "F.Fab")
		)
		(fp_line
			(start 0.12065 -0.3048)
			(end 0.67945 -0.3048)
			(stroke
				(width 0.1)
				(type default)
			)
			(layer "F.Fab")
		)
		(fp_line
			(start 0.12065 -0.2794)
			(end 0.12065 -0.3048)
			(stroke
				(width 0.1)
				(type default)
			)
			(layer "F.Fab")
		)
		(fp_line
			(start 0.67945 -0.3048)
			(end 0.67945 0.3048)
			(stroke
				(width 0.1)
				(type default)
			)
			(layer "F.Fab")
		)
		(fp_line
			(start 0.67945 0.3048)
			(end 0.120396 0.3048)
			(stroke
				(width 0.1)
				(type default)
			)
			(layer "F.Fab")
		)
		(pad "1" smd circle
			(at -0.40005 0)
			(size 0 0)
			(layers "F.Cu" "F.Mask" "F.Paste")
			(net "SVID_DIO1_CPU1_R")
		)
		(pad "2" smd circle
			(at 0.40005 0)
			(size 0 0)
			(layers "F.Cu" "F.Mask" "F.Paste")
			(net "SVID_DIO_PVCCD_HV_CPU1_R")
		)
	)
	(footprint ""
		(layer "F.Cu")
		(at 243.446808 -40.920162 -90)
		(property "Reference" "C1276"
			(at 0 0 270)
			(layer "F.SilkS")
			(hide yes)
			(effects
				(font
					(size 1.27 1.27)
				)
			)
		)
		(property "Value" ""
			(at 0 0 270)
			(layer "F.Fab")
			(effects
				(font
					(size 1.27 1.27)
				)
			)
		)
		(duplicate_pad_numbers_are_jumpers no)
		(fp_line
			(start -1.524 0.762)
			(end -1.524 -0.762)
			(stroke
				(width 0.1524)
				(type default)
			)
			(layer "F.SilkS")
		)
		(fp_line
			(start 1.524 0.762)
			(end -1.524 0.762)
			(stroke
				(width 0.1524)
				(type default)
			)
			(layer "F.SilkS")
		)
		(fp_line
			(start -1.524 -0.762)
			(end 1.524 -0.762)
			(stroke
				(width 0.1524)
				(type default)
			)
			(layer "F.SilkS")
		)
		(fp_line
			(start 1.524 -0.762)
			(end 1.524 0.762)
			(stroke
				(width 0.1524)
				(type default)
			)
			(layer "F.SilkS")
		)
		(fp_line
			(start -1.1049 0.724916)
			(end 1.1049 0.724916)
			(stroke
				(width 0.1)
				(type default)
			)
			(layer "F.Fab")
		)
		(fp_line
			(start 1.1049 0.724916)
			(end 1.1049 -0.724916)
			(stroke
				(width 0.1)
				(type default)
			)
			(layer "F.Fab")
		)
		(fp_line
			(start -1.1049 -0.724916)
			(end -1.1049 0.724916)
			(stroke
				(width 0.1)
				(type default)
			)
			(layer "F.Fab")
		)
		(fp_line
			(start 1.1049 -0.724916)
			(end -1.1049 -0.724916)
			(stroke
				(width 0.1)
				(type default)
			)
			(layer "F.Fab")
		)
		(pad "1" smd rect
			(at -0.889 0 90)
			(size 1.016 1.27)
			(layers "F.Cu" "F.Mask" "F.Paste")
			(net "P12V_E1S_0")
		)
		(pad "2" smd rect
			(at 0.889 0 90)
			(size 1.016 1.27)
			(layers "F.Cu" "F.Mask" "F.Paste")
			(net "GND")
		)
	)
	(footprint ""
		(layer "F.Cu")
		(at 28.081732 -406.687274)
		(property "Reference" "Q101"
			(at 0.40894 -2.037588 0)
			(unlocked yes)
			(layer "F.SilkS")
			(effects
				(font
					(size 0.7874 0.5842)
					(thickness 0.1524)
				)
				(justify left)
			)
		)
		(property "Value" ""
			(at 0 0 0)
			(layer "F.Fab")
			(effects
				(font
					(size 1.27 1.27)
				)
			)
		)
		(duplicate_pad_numbers_are_jumpers no)
		(fp_line
			(start -1.332738 -1.100074)
			(end -0.4826 -1.100074)
			(stroke
				(width 0.1524)
				(type default)
			)
			(layer "F.SilkS")
		)
		(fp_line
			(start -1.332738 1.100074)
			(end -1.332738 -1.100074)
			(stroke
				(width 0.1524)
				(type default)
			)
			(layer "F.SilkS")
		)
		(fp_line
			(start -0.4826 -1.100074)
			(end 0 -0.541274)
			(stroke
				(width 0.1524)
				(type default)
			)
			(layer "F.SilkS")
		)
		(fp_line
			(start 0 -0.541274)
			(end 0.4826 -1.100074)
			(stroke
				(width 0.1524)
				(type default)
			)
			(layer "F.SilkS")
		)
		(fp_line
			(start 0.4826 -1.100074)
			(end 1.332738 -1.100074)
			(stroke
				(width 0.1524)
				(type default)
			)
			(layer "F.SilkS")
		)
		(fp_line
			(start 1.332738 -1.100074)
			(end 1.332738 1.100074)
			(stroke
				(width 0.1524)
				(type default)
			)
			(layer "F.SilkS")
		)
		(fp_line
			(start 1.332738 1.100074)
			(end -1.332738 1.100074)
			(stroke
				(width 0.1524)
				(type default)
			)
			(layer "F.SilkS")
		)
		(fp_poly
			(pts
				(xy -1.895602 -1.706626) (xy -1.647444 -0.961898) (xy -2.392172 -1.210056)
			)
			(stroke
				(width 0)
				(type default)
			)
			(fill yes)
			(layer "F.SilkS")
		)
		(fp_line
			(start -0.674878 -1.100074)
			(end 0.674878 -1.100074)
			(stroke
				(width 0.1)
				(type default)
			)
			(layer "F.Fab")
		)
		(fp_line
			(start -0.674878 1.100074)
			(end -0.674878 -1.100074)
			(stroke
				(width 0.1)
				(type default)
			)
			(layer "F.Fab")
		)
		(fp_line
			(start 0.674878 -1.100074)
			(end 0.674878 1.100074)
			(stroke
				(width 0.1)
				(type default)
			)
			(layer "F.Fab")
		)
		(fp_line
			(start 0.674878 1.100074)
			(end -0.674878 1.100074)
			(stroke
				(width 0.1)
				(type default)
			)
			(layer "F.Fab")
		)
		(fp_poly
			(pts
				(xy -2.2352 -0.298958) (xy -2.2352 -1.001014) (xy -1.533144 -0.649986)
			)
			(stroke
				(width 0)
				(type default)
			)
			(fill yes)
			(layer "F.Fab")
		)
		(pad "1" smd rect
			(at -0.94996 -0.649986 90)
			(size 0.4318 0.508)
			(layers "F.Cu" "F.Mask" "F.Paste")
			(net "GND")
		)
		(pad "2" smd rect
			(at -0.94996 0 90)
			(size 0.4318 0.508)
			(layers "F.Cu" "F.Mask" "F.Paste")
			(net "GPU_FPGA_THERM_OVERT_N")
		)
		(pad "3" smd rect
			(at -0.94996 0.649986 90)
			(size 0.4318 0.508)
			(layers "F.Cu" "F.Mask" "F.Paste")
			(net "GPU_FPGA_THERM_OVERT_ISO_N")
		)
		(pad "4" smd rect
			(at 0.94996 0.649986 90)
			(size 0.4318 0.508)
			(layers "F.Cu" "F.Mask" "F.Paste")
			(net "GND")
		)
		(pad "5" smd rect
			(at 0.94996 0 90)
			(size 0.4318 0.508)
			(layers "F.Cu" "F.Mask" "F.Paste")
			(net "GPU_FPGA_THERM_OVERT")
		)
		(pad "6" smd rect
			(at 0.94996 -0.649986 90)
			(size 0.4318 0.508)
			(layers "F.Cu" "F.Mask" "F.Paste")
			(net "GPU_FPGA_THERM_OVERT")
		)
	)
	(footprint ""
		(layer "F.Cu")
		(at 353.248214 -251.375418 90)
		(property "Reference" "C1018"
			(at 0 0 90)
			(layer "F.SilkS")
			(hide yes)
			(effects
				(font
					(size 1.27 1.27)
				)
			)
		)
		(property "Value" ""
			(at 0 0 90)
			(layer "F.Fab")
			(effects
				(font
					(size 1.27 1.27)
				)
			)
		)
		(duplicate_pad_numbers_are_jumpers no)
		(fp_line
			(start 0.7874 -0.4064)
			(end 0.7874 0.4064)
			(stroke
				(width 0.1524)
				(type default)
			)
			(layer "F.SilkS")
		)
		(fp_line
			(start -0.7874 -0.4064)
			(end 0.7874 -0.4064)
			(stroke
				(width 0.1524)
				(type default)
			)
			(layer "F.SilkS")
		)
		(fp_line
			(start 0.7874 0.4064)
			(end -0.7874 0.4064)
			(stroke
				(width 0.1524)
				(type default)
			)
			(layer "F.SilkS")
		)
		(fp_line
			(start -0.7874 0.4064)
			(end -0.7874 -0.4064)
			(stroke
				(width 0.1524)
				(type default)
			)
			(layer "F.SilkS")
		)
		(fp_line
			(start -0.12065 -0.305054)
			(end -0.12065 -0.2794)
			(stroke
				(width 0.1)
				(type default)
			)
			(layer "F.Fab")
		)
		(fp_line
			(start -0.67945 -0.305054)
			(end -0.12065 -0.305054)
			(stroke
				(width 0.1)
				(type default)
			)
			(layer "F.Fab")
		)
		(fp_line
			(start 0.67945 -0.3048)
			(end 0.67945 0.3048)
			(stroke
				(width 0.1)
				(type default)
			)
			(layer "F.Fab")
		)
		(fp_line
			(start 0.12065 -0.3048)
			(end 0.67945 -0.3048)
			(stroke
				(width 0.1)
				(type default)
			)
			(layer "F.Fab")
		)
		(fp_line
			(start 0.12065 -0.2794)
			(end 0.12065 -0.3048)
			(stroke
				(width 0.1)
				(type default)
			)
			(layer "F.Fab")
		)
		(fp_line
			(start -0.12065 -0.2794)
			(end 0.12065 -0.2794)
			(stroke
				(width 0.1)
				(type default)
			)
			(layer "F.Fab")
		)
		(fp_line
			(start 0.120396 0.2794)
			(end -0.12065 0.2794)
			(stroke
				(width 0.1)
				(type default)
			)
			(layer "F.Fab")
		)
		(fp_line
			(start -0.12065 0.2794)
			(end -0.12065 0.3048)
			(stroke
				(width 0.1)
				(type default)
			)
			(layer "F.Fab")
		)
		(fp_line
			(start 0.67945 0.3048)
			(end 0.120396 0.3048)
			(stroke
				(width 0.1)
				(type default)
			)
			(layer "F.Fab")
		)
		(fp_line
			(start 0.120396 0.3048)
			(end 0.120396 0.2794)
			(stroke
				(width 0.1)
				(type default)
			)
			(layer "F.Fab")
		)
		(fp_line
			(start -0.12065 0.3048)
			(end -0.67945 0.3048)
			(stroke
				(width 0.1)
				(type default)
			)
			(layer "F.Fab")
		)
		(fp_line
			(start -0.67945 0.3048)
			(end -0.67945 -0.305054)
			(stroke
				(width 0.1)
				(type default)
			)
			(layer "F.Fab")
		)
		(pad "1" smd circle
			(at -0.40005 0 90)
			(size 0 0)
			(layers "F.Cu" "F.Mask" "F.Paste")
			(net "PVCCIN_CPU0")
		)
		(pad "2" smd circle
			(at 0.40005 0 90)
			(size 0 0)
			(layers "F.Cu" "F.Mask" "F.Paste")
			(net "GND")
		)
	)
)
